(kicad_pcb
	(version 20260206)
	(generator "pcbnew")
	(generator_version "10.0")
	(general
		(thickness 1.6)
		(legacy_teardrops no)
	)
	(paper "A4")
	(title_block
		(title "baseboard — 13948-1b.1110WZS1818.brd")
		(comment 1 "Honey Badger (Wiwynn) / footprints 1946-1952 of 2523")
	)
	(layers
		(0 "F.Cu" signal "TOP")
		(4 "In1.Cu" signal "L2GND")
		(6 "In2.Cu" signal "L3")
		(8 "In3.Cu" signal "L4VCC")
		(10 "In4.Cu" signal "L5VCC")
		(12 "In5.Cu" signal "L6")
		(14 "In6.Cu" signal "L7GND")
		(2 "B.Cu" signal "BOTTOM")
		(9 "F.Adhes" user "F.Adhesive")
		(11 "B.Adhes" user "B.Adhesive")
		(13 "F.Paste" user "Package Geometry/Pastemask Top")
		(15 "B.Paste" user "Package Geometry/Pastemask Bottom")
		(5 "F.SilkS" user "Ref Des/Silkscreen Top")
		(7 "B.SilkS" user "Ref Des/Silkscreen Bottom")
		(1 "F.Mask" user "Board Geometry/Soldermask Top")
		(3 "B.Mask" user "Board Geometry/Soldermask Bottom")
		(17 "Dwgs.User" user "User.Drawings")
		(19 "Cmts.User" user "User.Comments")
		(21 "Eco1.User" user "User.Eco1")
		(23 "Eco2.User" user "User.Eco2")
		(25 "Edge.Cuts" user "Board Geometry/Outline")
		(27 "Margin" user)
		(31 "F.CrtYd" user "Package Geometry/Place Bound Top")
		(29 "B.CrtYd" user "Package Geometry/Place Bound Bottom")
		(35 "F.Fab" user "Ref Des/Assembly Top")
		(33 "B.Fab" user "Ref Des/Assembly Bottom")
	)
	(footprint ""
		(layer "B.Cu")
		(at 100.08616 -31.623)
		(property "Reference" "SC870"
			(at 0 0 0)
			(layer "B.SilkS")
			(hide yes)
			(effects
				(font
					(size 1.27 1.27)
				)
				(justify mirror)
			)
		)
		(property "Value" "SCD22U6D3V1MX-1-GP"
			(at 2.8321 -1.7399 0)
			(unlocked yes)
			(layer "B.Fab")
			(hide yes)
			(effects
				(font
					(size 1.016 1.016)
					(thickness 0.1524)
				)
				(justify mirror)
			)
		)
		(property "Device Type" "C0201H13"
			(at 2.8321 -3.2639 0)
			(unlocked yes)
			(layer "B.Fab")
			(hide yes)
			(effects
				(font
					(size 1.016 1.016)
					(thickness 0.1524)
				)
				(justify mirror)
			)
		)
		(duplicate_pad_numbers_are_jumpers no)
		(fp_rect
			(start 0.2794 0.6477)
			(end -0.2794 -0.6477)
			(stroke
				(width 0)
				(type default)
			)
			(fill no)
			(layer "B.CrtYd")
		)
		(fp_rect
			(start 0.2794 0.6477)
			(end -0.2794 -0.6477)
			(stroke
				(width 0)
				(type default)
			)
			(fill no)
			(layer "B.Fab")
		)
		(pad "1" smd custom
			(at 0 -0.2794 180)
			(size 0.0762 0.0762)
			(layers "B.Cu" "B.Mask" "B.Paste")
			(net "PCIE_SAS_C_CPU_RX_N4")
			(options
				(clearance outline)
				(anchor circle)
			)
			(primitives
				(gr_poly
					(pts
						(arc
							(start 0.1524 0.127)
							(mid 0.137521 0.162921)
							(end 0.1016 0.1778)
						)
						(arc
							(start -0.1016 0.1778)
							(mid -0.137521 0.162921)
							(end -0.1524 0.127)
						)
						(arc
							(start -0.1524 -0.127)
							(mid -0.137521 -0.162921)
							(end -0.1016 -0.1778)
						)
						(arc
							(start 0.1016 -0.1778)
							(mid 0.137521 -0.162921)
							(end 0.1524 -0.127)
						)
					)
					(width 0)
					(fill yes)
				)
			)
		)
		(pad "2" smd custom
			(at 0 0.2794 180)
			(size 0.0762 0.0762)
			(layers "B.Cu" "B.Mask" "B.Paste")
			(net "PCIE_SAS_CPU_RX_N4")
			(options
				(clearance outline)
				(anchor circle)
			)
			(primitives
				(gr_poly
					(pts
						(arc
							(start 0.1524 0.127)
							(mid 0.137521 0.162921)
							(end 0.1016 0.1778)
						)
						(arc
							(start -0.1016 0.1778)
							(mid -0.137521 0.162921)
							(end -0.1524 0.127)
						)
						(arc
							(start -0.1524 -0.127)
							(mid -0.137521 -0.162921)
							(end -0.1016 -0.1778)
						)
						(arc
							(start 0.1016 -0.1778)
							(mid 0.137521 -0.162921)
							(end 0.1524 -0.127)
						)
					)
					(width 0)
					(fill yes)
				)
			)
		)
	)
	(footprint ""
		(layer "B.Cu")
		(at 290.059872 -176.729136 90)
		(property "Reference" "C210"
			(at 0 0 90)
			(layer "B.SilkS")
			(hide yes)
			(effects
				(font
					(size 1.27 1.27)
				)
				(justify mirror)
			)
		)
		(property "Value" "SC1U6D3V3KX-2GP"
			(at 0 -2.8194 90)
			(unlocked yes)
			(layer "B.Fab")
			(hide yes)
			(effects
				(font
					(size 1.016 1.016)
					(thickness 0.1524)
				)
				(justify mirror)
			)
		)
		(property "Device Type" "C603H36"
			(at 0 -4.3434 90)
			(unlocked yes)
			(layer "B.Fab")
			(hide yes)
			(effects
				(font
					(size 1.016 1.016)
					(thickness 0.1524)
				)
				(justify mirror)
			)
		)
		(duplicate_pad_numbers_are_jumpers no)
		(fp_line
			(start -0.508 0)
			(end 0.508 0)
			(stroke
				(width 0.2032)
				(type default)
			)
			(layer "B.SilkS")
		)
		(fp_rect
			(start 0.5842 1.3335)
			(end -0.5842 -1.3335)
			(stroke
				(width 0)
				(type default)
			)
			(fill no)
			(layer "B.CrtYd")
		)
		(fp_rect
			(start 0.5842 1.3335)
			(end -0.5842 -1.3335)
			(stroke
				(width 0)
				(type default)
			)
			(fill no)
			(layer "B.Fab")
		)
		(pad "1" smd custom
			(at 0 -0.762 270)
			(size 0.2159 0.2159)
			(layers "B.Cu" "B.Mask" "B.Paste")
			(net "P3V3_STBY")
			(options
				(clearance outline)
				(anchor circle)
			)
			(primitives
				(gr_poly
					(pts
						(arc
							(start -0.3302 0.4318)
							(mid -0.402042 0.402042)
							(end -0.4318 0.3302)
						)
						(arc
							(start -0.4318 -0.3302)
							(mid -0.402042 -0.402042)
							(end -0.3302 -0.4318)
						)
						(arc
							(start 0.3302 -0.4318)
							(mid 0.402042 -0.402042)
							(end 0.4318 -0.3302)
						)
						(arc
							(start 0.4318 0.3302)
							(mid 0.402042 0.402042)
							(end 0.3302 0.4318)
						)
					)
					(width 0)
					(fill yes)
				)
			)
		)
		(pad "2" smd custom
			(at 0 0.762 270)
			(size 0.2159 0.2159)
			(layers "B.Cu" "B.Mask" "B.Paste")
			(net "GND")
			(options
				(clearance outline)
				(anchor circle)
			)
			(primitives
				(gr_poly
					(pts
						(arc
							(start -0.3302 0.4318)
							(mid -0.402042 0.402042)
							(end -0.4318 0.3302)
						)
						(arc
							(start -0.4318 -0.3302)
							(mid -0.402042 -0.402042)
							(end -0.3302 -0.4318)
						)
						(arc
							(start 0.3302 -0.4318)
							(mid 0.402042 -0.402042)
							(end 0.4318 -0.3302)
						)
						(arc
							(start 0.4318 0.3302)
							(mid 0.402042 0.402042)
							(end 0.3302 0.4318)
						)
					)
					(width 0)
					(fill yes)
				)
			)
		)
	)
	(footprint ""
		(layer "B.Cu")
		(at 120.91797 -85.979 -90)
		(property "Reference" "SC1193"
			(at 0 0 90)
			(layer "B.SilkS")
			(hide yes)
			(effects
				(font
					(size 1.27 1.27)
				)
				(justify mirror)
			)
		)
		(property "Value" "SCD1U6D3V1KX-GP"
			(at 2.8321 -1.7399 270)
			(unlocked yes)
			(layer "B.Fab")
			(hide yes)
			(effects
				(font
					(size 1.016 1.016)
					(thickness 0.1524)
				)
				(justify mirror)
			)
		)
		(property "Device Type" "C0201H13"
			(at 2.8321 -3.2639 270)
			(unlocked yes)
			(layer "B.Fab")
			(hide yes)
			(effects
				(font
					(size 1.016 1.016)
					(thickness 0.1524)
				)
				(justify mirror)
			)
		)
		(duplicate_pad_numbers_are_jumpers no)
		(fp_rect
			(start 0.2794 0.6477)
			(end -0.2794 -0.6477)
			(stroke
				(width 0)
				(type default)
			)
			(fill no)
			(layer "B.CrtYd")
		)
		(fp_rect
			(start 0.2794 0.6477)
			(end -0.2794 -0.6477)
			(stroke
				(width 0)
				(type default)
			)
			(fill no)
			(layer "B.Fab")
		)
		(pad "1" smd custom
			(at 0 -0.2794 90)
			(size 0.0762 0.0762)
			(layers "B.Cu" "B.Mask" "B.Paste")
			(net "GB_VDDA")
			(options
				(clearance outline)
				(anchor circle)
			)
			(primitives
				(gr_poly
					(pts
						(arc
							(start 0.1524 0.127)
							(mid 0.137521 0.162921)
							(end 0.1016 0.1778)
						)
						(arc
							(start -0.1016 0.1778)
							(mid -0.137521 0.162921)
							(end -0.1524 0.127)
						)
						(arc
							(start -0.1524 -0.127)
							(mid -0.137521 -0.162921)
							(end -0.1016 -0.1778)
						)
						(arc
							(start 0.1016 -0.1778)
							(mid 0.137521 -0.162921)
							(end 0.1524 -0.127)
						)
					)
					(width 0)
					(fill yes)
				)
			)
		)
		(pad "2" smd custom
			(at 0 0.2794 90)
			(size 0.0762 0.0762)
			(layers "B.Cu" "B.Mask" "B.Paste")
			(net "GND")
			(options
				(clearance outline)
				(anchor circle)
			)
			(primitives
				(gr_poly
					(pts
						(arc
							(start 0.1524 0.127)
							(mid 0.137521 0.162921)
							(end 0.1016 0.1778)
						)
						(arc
							(start -0.1016 0.1778)
							(mid -0.137521 0.162921)
							(end -0.1524 0.127)
						)
						(arc
							(start -0.1524 -0.127)
							(mid -0.137521 -0.162921)
							(end -0.1016 -0.1778)
						)
						(arc
							(start 0.1016 -0.1778)
							(mid 0.137521 -0.162921)
							(end 0.1524 -0.127)
						)
					)
					(width 0)
					(fill yes)
				)
			)
		)
	)
	(footprint ""
		(layer "B.Cu")
		(at 79.502 -23.114)
		(property "Reference" "SR932"
			(at 0 0 0)
			(layer "B.SilkS")
			(hide yes)
			(effects
				(font
					(size 1.27 1.27)
				)
				(justify mirror)
			)
		)
		(property "Value" "4K7R2F-GP"
			(at -0.064008 -3.993896 0)
			(unlocked yes)
			(layer "B.Fab")
			(hide yes)
			(effects
				(font
					(size 1.016 1.016)
					(thickness 0.1524)
				)
				(justify mirror)
			)
		)
		(property "Device Type" "R402H16"
			(at -0.064008 -5.517896 0)
			(unlocked yes)
			(layer "B.Fab")
			(hide yes)
			(effects
				(font
					(size 1.016 1.016)
					(thickness 0.1524)
				)
				(justify mirror)
			)
		)
		(duplicate_pad_numbers_are_jumpers no)
		(fp_line
			(start -0.508 -0.9398)
			(end 0.508 -0.9398)
			(stroke
				(width 0.1524)
				(type default)
			)
			(layer "B.SilkS")
		)
		(fp_line
			(start 0.508 -0.9398)
			(end 0.508 0.9398)
			(stroke
				(width 0.1524)
				(type default)
			)
			(layer "B.SilkS")
		)
		(fp_rect
			(start 0.508 0.9398)
			(end -0.508 -0.9398)
			(stroke
				(width 0)
				(type default)
			)
			(fill no)
			(layer "B.CrtYd")
		)
		(fp_rect
			(start 0.508 0.9398)
			(end -0.508 -0.9398)
			(stroke
				(width 0)
				(type default)
			)
			(fill no)
			(layer "B.Fab")
		)
		(pad "1" smd custom
			(at 0 -0.4445 180)
			(size 0.1397 0.1397)
			(layers "B.Cu" "B.Mask" "B.Paste")
			(net "P3V3_STBY")
			(options
				(clearance outline)
				(anchor circle)
			)
			(primitives
				(gr_poly
					(pts
						(arc
							(start -0.1778 0.2794)
							(mid -0.249642 0.249642)
							(end -0.2794 0.1778)
						)
						(arc
							(start -0.2794 -0.1778)
							(mid -0.249642 -0.249642)
							(end -0.1778 -0.2794)
						)
						(arc
							(start 0.1778 -0.2794)
							(mid 0.249642 -0.249642)
							(end 0.2794 -0.1778)
						)
						(arc
							(start 0.2794 0.1778)
							(mid 0.249642 0.249642)
							(end 0.1778 0.2794)
						)
					)
					(width 0)
					(fill yes)
				)
			)
		)
		(pad "2" smd custom
			(at 0 0.4445 180)
			(size 0.1397 0.1397)
			(layers "B.Cu" "B.Mask" "B.Paste")
			(net "PG_STAT_P0V955_C")
			(options
				(clearance outline)
				(anchor circle)
			)
			(primitives
				(gr_poly
					(pts
						(arc
							(start -0.1778 0.2794)
							(mid -0.249642 0.249642)
							(end -0.2794 0.1778)
						)
						(arc
							(start -0.2794 -0.1778)
							(mid -0.249642 -0.249642)
							(end -0.1778 -0.2794)
						)
						(arc
							(start 0.1778 -0.2794)
							(mid 0.249642 -0.249642)
							(end 0.2794 -0.1778)
						)
						(arc
							(start 0.2794 0.1778)
							(mid 0.249642 0.249642)
							(end 0.1778 0.2794)
						)
					)
					(width 0)
					(fill yes)
				)
			)
		)
	)
	(footprint ""
		(layer "B.Cu")
		(at 88.91397 -137.795 90)
		(property "Reference" "SC1119"
			(at 0 0 90)
			(layer "B.SilkS")
			(hide yes)
			(effects
				(font
					(size 1.27 1.27)
				)
				(justify mirror)
			)
		)
		(property "Value" "SCD1U16V2KX-3GP"
			(at -1.1811 -2.7051 90)
			(unlocked yes)
			(layer "B.Fab")
			(hide yes)
			(effects
				(font
					(size 1.016 1.016)
					(thickness 0.1524)
				)
				(justify mirror)
			)
		)
		(property "Device Type" "C402H22"
			(at -1.1811 -4.2291 90)
			(unlocked yes)
			(layer "B.Fab")
			(hide yes)
			(effects
				(font
					(size 1.016 1.016)
					(thickness 0.1524)
				)
				(justify mirror)
			)
		)
		(duplicate_pad_numbers_are_jumpers no)
		(fp_rect
			(start 0.4318 0.9525)
			(end -0.4318 -0.9525)
			(stroke
				(width 0)
				(type default)
			)
			(fill no)
			(layer "B.CrtYd")
		)
		(fp_rect
			(start 0.4318 0.9525)
			(end -0.4318 -0.9525)
			(stroke
				(width 0)
				(type default)
			)
			(fill no)
			(layer "B.Fab")
		)
		(pad "1" smd custom
			(at 0 -0.4445 270)
			(size 0.1524 0.1524)
			(layers "B.Cu" "B.Mask" "B.Paste")
			(net "P3V3_STBY")
			(options
				(clearance outline)
				(anchor circle)
			)
			(primitives
				(gr_poly
					(pts
						(arc
							(start 0.3048 0.2032)
							(mid 0.275042 0.275042)
							(end 0.2032 0.3048)
						)
						(arc
							(start -0.2032 0.3048)
							(mid -0.275042 0.275042)
							(end -0.3048 0.2032)
						)
						(arc
							(start -0.3048 -0.2032)
							(mid -0.275042 -0.275042)
							(end -0.2032 -0.3048)
						)
						(arc
							(start 0.2032 -0.3048)
							(mid 0.275042 -0.275042)
							(end 0.3048 -0.2032)
						)
					)
					(width 0)
					(fill yes)
				)
			)
		)
		(pad "2" smd custom
			(at 0 0.4445 270)
			(size 0.1524 0.1524)
			(layers "B.Cu" "B.Mask" "B.Paste")
			(net "GND")
			(options
				(clearance outline)
				(anchor circle)
			)
			(primitives
				(gr_poly
					(pts
						(arc
							(start 0.3048 0.2032)
							(mid 0.275042 0.275042)
							(end 0.2032 0.3048)
						)
						(arc
							(start -0.2032 0.3048)
							(mid -0.275042 0.275042)
							(end -0.3048 0.2032)
						)
						(arc
							(start -0.3048 -0.2032)
							(mid -0.275042 -0.275042)
							(end -0.2032 -0.3048)
						)
						(arc
							(start 0.2032 -0.3048)
							(mid 0.275042 -0.275042)
							(end 0.3048 -0.2032)
						)
					)
					(width 0)
					(fill yes)
				)
			)
		)
	)
	(footprint ""
		(layer "B.Cu")
		(at 100.838 -239.395)
		(property "Reference" "SR844"
			(at 0 0 0)
			(layer "B.SilkS")
			(hide yes)
			(effects
				(font
					(size 1.27 1.27)
				)
				(justify mirror)
			)
		)
		(property "Value" "4K7R2F-GP"
			(at -0.064008 -3.993896 0)
			(unlocked yes)
			(layer "B.Fab")
			(hide yes)
			(effects
				(font
					(size 1.016 1.016)
					(thickness 0.1524)
				)
				(justify mirror)
			)
		)
		(property "Device Type" "R402H16"
			(at -0.064008 -5.517896 0)
			(unlocked yes)
			(layer "B.Fab")
			(hide yes)
			(effects
				(font
					(size 1.016 1.016)
					(thickness 0.1524)
				)
				(justify mirror)
			)
		)
		(duplicate_pad_numbers_are_jumpers no)
		(fp_line
			(start -0.508 -0.9398)
			(end 0.508 -0.9398)
			(stroke
				(width 0.1524)
				(type default)
			)
			(layer "B.SilkS")
		)
		(fp_line
			(start 0.508 -0.9398)
			(end 0.508 0.9398)
			(stroke
				(width 0.1524)
				(type default)
			)
			(layer "B.SilkS")
		)
		(fp_rect
			(start 0.508 0.9398)
			(end -0.508 -0.9398)
			(stroke
				(width 0)
				(type default)
			)
			(fill no)
			(layer "B.CrtYd")
		)
		(fp_rect
			(start 0.508 0.9398)
			(end -0.508 -0.9398)
			(stroke
				(width 0)
				(type default)
			)
			(fill no)
			(layer "B.Fab")
		)
		(pad "1" smd custom
			(at 0 -0.4445 180)
			(size 0.1397 0.1397)
			(layers "B.Cu" "B.Mask" "B.Paste")
			(net "SAS_FAULT_LED1")
			(options
				(clearance outline)
				(anchor circle)
			)
			(primitives
				(gr_poly
					(pts
						(arc
							(start -0.1778 0.2794)
							(mid -0.249642 0.249642)
							(end -0.2794 0.1778)
						)
						(arc
							(start -0.2794 -0.1778)
							(mid -0.249642 -0.249642)
							(end -0.1778 -0.2794)
						)
						(arc
							(start 0.1778 -0.2794)
							(mid 0.249642 -0.249642)
							(end 0.2794 -0.1778)
						)
						(arc
							(start 0.2794 0.1778)
							(mid 0.249642 0.249642)
							(end 0.1778 0.2794)
						)
					)
					(width 0)
					(fill yes)
				)
			)
		)
		(pad "2" smd custom
			(at 0 0.4445 180)
			(size 0.1397 0.1397)
			(layers "B.Cu" "B.Mask" "B.Paste")
			(net "P3V3_STBY")
			(options
				(clearance outline)
				(anchor circle)
			)
			(primitives
				(gr_poly
					(pts
						(arc
							(start -0.1778 0.2794)
							(mid -0.249642 0.249642)
							(end -0.2794 0.1778)
						)
						(arc
							(start -0.2794 -0.1778)
							(mid -0.249642 -0.249642)
							(end -0.1778 -0.2794)
						)
						(arc
							(start 0.1778 -0.2794)
							(mid 0.249642 -0.249642)
							(end 0.2794 -0.1778)
						)
						(arc
							(start 0.2794 0.1778)
							(mid 0.249642 0.249642)
							(end 0.1778 0.2794)
						)
					)
					(width 0)
					(fill yes)
				)
			)
		)
	)
	(footprint ""
		(layer "B.Cu")
		(at 90.932 -3.429)
		(property "Reference" "SC1051"
			(at 0 0 0)
			(layer "B.SilkS")
			(hide yes)
			(effects
				(font
					(size 1.27 1.27)
				)
				(justify mirror)
			)
		)
		(property "Value" "SCD1U16V2KX-3GP"
			(at -1.1811 -2.7051 0)
			(unlocked yes)
			(layer "B.Fab")
			(hide yes)
			(effects
				(font
					(size 1.016 1.016)
					(thickness 0.1524)
				)
				(justify mirror)
			)
		)
		(property "Device Type" "C402H22"
			(at -1.1811 -4.2291 0)
			(unlocked yes)
			(layer "B.Fab")
			(hide yes)
			(effects
				(font
					(size 1.016 1.016)
					(thickness 0.1524)
				)
				(justify mirror)
			)
		)
		(duplicate_pad_numbers_are_jumpers no)
		(fp_rect
			(start 0.4318 0.9525)
			(end -0.4318 -0.9525)
			(stroke
				(width 0)
				(type default)
			)
			(fill no)
			(layer "B.CrtYd")
		)
		(fp_rect
			(start 0.4318 0.9525)
			(end -0.4318 -0.9525)
			(stroke
				(width 0)
				(type default)
			)
			(fill no)
			(layer "B.Fab")
		)
		(pad "1" smd custom
			(at 0 -0.4445 180)
			(size 0.1524 0.1524)
			(layers "B.Cu" "B.Mask" "B.Paste")
			(net "P0V955_C")
			(options
				(clearance outline)
				(anchor circle)
			)
			(primitives
				(gr_poly
					(pts
						(arc
							(start 0.3048 0.2032)
							(mid 0.275042 0.275042)
							(end 0.2032 0.3048)
						)
						(arc
							(start -0.2032 0.3048)
							(mid -0.275042 0.275042)
							(end -0.3048 0.2032)
						)
						(arc
							(start -0.3048 -0.2032)
							(mid -0.275042 -0.275042)
							(end -0.2032 -0.3048)
						)
						(arc
							(start 0.2032 -0.3048)
							(mid 0.275042 -0.275042)
							(end 0.3048 -0.2032)
						)
					)
					(width 0)
					(fill yes)
				)
			)
		)
		(pad "2" smd custom
			(at 0 0.4445 180)
			(size 0.1524 0.1524)
			(layers "B.Cu" "B.Mask" "B.Paste")
			(net "GND")
			(options
				(clearance outline)
				(anchor circle)
			)
			(primitives
				(gr_poly
					(pts
						(arc
							(start 0.3048 0.2032)
							(mid 0.275042 0.275042)
							(end 0.2032 0.3048)
						)
						(arc
							(start -0.2032 0.3048)
							(mid -0.275042 0.275042)
							(end -0.3048 0.2032)
						)
						(arc
							(start -0.3048 -0.2032)
							(mid -0.275042 -0.275042)
							(end -0.2032 -0.3048)
						)
						(arc
							(start 0.2032 -0.3048)
							(mid 0.275042 -0.275042)
							(end 0.3048 -0.2032)
						)
					)
					(width 0)
					(fill yes)
				)
			)
		)
	)
)
